# BASEBOARD_FAB2 (Tioga Pass) — schematic netlist excerpt (pin names and nets, part order shuffled) for the footprints in the layout excerpt that follows; sources: Cadence DE-HDL packaged netlist, KiCad conversion of Wiwynn_Tioga_Pass_MB.brd

C9T7  CAP_A  0.01UF 25V 10% X7R  pkg 0402V  page 78 : A = M_G_VREF ; B = GND
C25W69  CAP  4.7UF 6.3V 10% X6S  pkg 0603  page 149 : A = VCC_VA_3V3 ; B = GND
R4T4  RES  10.0 1% CHIP  pkg 0402  page 99 : A = SMB_DDR_ABC_SDA_G_R ; B = SMB_DDR_ABC_SDA_G

(kicad_pcb
	(version 20260206)
	(generator "pcbnew")
	(generator_version "10.0")
	(general
		(thickness 1.6)
		(legacy_teardrops no)
	)
	(paper "A4")
	(title_block
		(title "Wiwynn_Tioga_Pass_MB.brd")
		(comment 1 "Tioga Pass / footprints 2673-2675 of 4770")
	)
	(layers
		(0 "F.Cu" signal "TOP")
		(4 "In1.Cu" signal "L2GND")
		(6 "In2.Cu" signal "L3")
		(8 "In3.Cu" signal "L4GND")
		(10 "In4.Cu" signal "L5")
		(12 "In5.Cu" signal "L6GND")
		(14 "In6.Cu" signal "L7VCC")
		(16 "In7.Cu" signal "L8VCC")
		(18 "In8.Cu" signal "L9GND")
		(20 "In9.Cu" signal "L10")
		(22 "In10.Cu" signal "L11GND")
		(24 "In11.Cu" signal "L12")
		(26 "In12.Cu" signal "L13GND")
		(2 "B.Cu" signal "BOTTOM")
		(9 "F.Adhes" user "F.Adhesive")
		(11 "B.Adhes" user "B.Adhesive")
		(13 "F.Paste" user "Package Geometry/Pastemask Top")
		(15 "B.Paste" user "Package Geometry/Pastemask Bottom")
		(5 "F.SilkS" user "Ref Des/Silkscreen Top")
		(7 "B.SilkS" user "Ref Des/Silkscreen Bottom")
		(1 "F.Mask" user "Board Geometry/Soldermask Top")
		(3 "B.Mask" user "Board Geometry/Soldermask Bottom")
		(17 "Dwgs.User" user "User.Drawings")
		(19 "Cmts.User" user "User.Comments")
		(21 "Eco1.User" user "User.Eco1")
		(23 "Eco2.User" user "User.Eco2")
		(25 "Edge.Cuts" user "Board Geometry/Outline")
		(27 "Margin" user)
		(31 "F.CrtYd" user "Package Geometry/Place Bound Top")
		(29 "B.CrtYd" user "Package Geometry/Place Bound Bottom")
		(35 "F.Fab" user "Ref Des/Assembly Top")
		(33 "B.Fab" user "Ref Des/Assembly Bottom")
	)
	(footprint ""
		(layer "B.Cu")
		(at 30.452568 -17.723612 90)
		(property "Reference" "C9T7"
			(at 0 0 90)
			(layer "B.SilkS")
			(hide yes)
			(effects
				(font
					(size 1.27 1.27)
				)
				(justify mirror)
			)
		)
		(property "Value" ""
			(at 0 0 90)
			(layer "B.Fab")
			(effects
				(font
					(size 1.27 1.27)
				)
				(justify mirror)
			)
		)
		(duplicate_pad_numbers_are_jumpers no)
		(fp_poly
			(pts
				(xy -0.3048 -0.1016) (xy -0.3048 0.9906) (xy 0.3048 0.9906) (xy 0.3048 -0.1016)
			)
			(stroke
				(width 0)
				(type default)
			)
			(fill no)
			(layer "B.CrtYd")
		)
		(fp_line
			(start 0.3048 -0.1016)
			(end 0.3048 0.9906)
			(stroke
				(width 0.1)
				(type default)
			)
			(layer "B.Fab")
		)
		(fp_line
			(start -0.3048 -0.1016)
			(end 0.3048 -0.1016)
			(stroke
				(width 0.1)
				(type default)
			)
			(layer "B.Fab")
		)
		(fp_line
			(start 0.3048 0.9906)
			(end -0.3048 0.9906)
			(stroke
				(width 0.1)
				(type default)
			)
			(layer "B.Fab")
		)
		(fp_line
			(start -0.3048 0.9906)
			(end -0.3048 -0.1016)
			(stroke
				(width 0.1)
				(type default)
			)
			(layer "B.Fab")
		)
		(pad "1" smd rect
			(at 0 0 270)
			(size 0.508 0.508)
			(layers "B.Cu" "B.Mask" "B.Paste")
			(net "M_G_VREF")
		)
		(pad "2" smd rect
			(at 0 0.889 270)
			(size 0.508 0.508)
			(layers "B.Cu" "B.Mask" "B.Paste")
			(net "GND")
		)
		(zone
			(layer "B.Cu")
			(hatch none 0.5)
			(connect_pads
				(clearance 0)
			)
			(min_thickness 0.25)
			(keepout
				(tracks allowed)
				(vias not_allowed)
				(pads allowed)
				(copperpour not_allowed)
				(footprints allowed)
			)
			(placement
				(enabled no)
				(sheetname "")
			)
			(fill
				(thermal_gap 0.5)
				(thermal_bridge_width 0.5)
				(island_removal_mode 0)
			)
			(polygon
				(pts
					(xy 30.706568 -17.977612) (xy 30.706568 -17.469612) (xy 31.087568 -17.469612) (xy 31.087568 -17.977612)
				)
			)
		)
		(zone
			(layer "B.Cu")
			(hatch none 0.5)
			(connect_pads
				(clearance 0)
			)
			(min_thickness 0.25)
			(keepout
				(tracks not_allowed)
				(vias allowed)
				(pads allowed)
				(copperpour not_allowed)
				(footprints allowed)
			)
			(placement
				(enabled no)
				(sheetname "")
			)
			(fill
				(thermal_gap 0.5)
				(thermal_bridge_width 0.5)
				(island_removal_mode 0)
			)
			(polygon
				(pts
					(xy 31.087568 -17.977612) (xy 31.087568 -17.469612) (xy 30.706568 -17.469612) (xy 30.706568 -17.977612)
				)
			)
		)
	)
	(footprint ""
		(layer "B.Cu")
		(at 321.1957 -32.93618 90)
		(property "Reference" "R4T4"
			(at 0 0 90)
			(layer "B.SilkS")
			(hide yes)
			(effects
				(font
					(size 1.27 1.27)
				)
				(justify mirror)
			)
		)
		(property "Value" ""
			(at 0 0 90)
			(layer "B.Fab")
			(effects
				(font
					(size 1.27 1.27)
				)
				(justify mirror)
			)
		)
		(duplicate_pad_numbers_are_jumpers no)
		(fp_poly
			(pts
				(xy 0.2794 -0.1016) (xy -0.2794 -0.1016) (xy -0.2794 0.9906) (xy 0.2794 0.9906)
			)
			(stroke
				(width 0)
				(type default)
			)
			(fill no)
			(layer "B.CrtYd")
		)
		(fp_line
			(start 0.2794 -0.1016)
			(end 0.2794 0.9906)
			(stroke
				(width 0.1)
				(type default)
			)
			(layer "B.Fab")
		)
		(fp_line
			(start -0.2794 -0.1016)
			(end 0.2794 -0.1016)
			(stroke
				(width 0.1)
				(type default)
			)
			(layer "B.Fab")
		)
		(fp_line
			(start 0.2794 0.9906)
			(end -0.2794 0.9906)
			(stroke
				(width 0.1)
				(type default)
			)
			(layer "B.Fab")
		)
		(fp_line
			(start -0.2794 0.9906)
			(end -0.2794 -0.1016)
			(stroke
				(width 0.1)
				(type default)
			)
			(layer "B.Fab")
		)
		(pad "1" smd rect
			(at 0 0 270)
			(size 0.508 0.508)
			(layers "B.Cu" "B.Mask" "B.Paste")
			(net "SMB_DDR_ABC_SDA_G_R")
		)
		(pad "2" smd rect
			(at 0 0.889 270)
			(size 0.508 0.508)
			(layers "B.Cu" "B.Mask" "B.Paste")
			(net "SMB_DDR_ABC_SDA_G")
		)
		(zone
			(layer "B.Cu")
			(hatch none 0.5)
			(connect_pads
				(clearance 0)
			)
			(min_thickness 0.25)
			(keepout
				(tracks allowed)
				(vias not_allowed)
				(pads allowed)
				(copperpour not_allowed)
				(footprints allowed)
			)
			(placement
				(enabled no)
				(sheetname "")
			)
			(fill
				(thermal_gap 0.5)
				(thermal_bridge_width 0.5)
				(island_removal_mode 0)
			)
			(polygon
				(pts
					(xy 321.4497 -33.19018) (xy 321.4497 -32.68218) (xy 321.8307 -32.68218) (xy 321.8307 -33.19018)
				)
			)
		)
		(zone
			(layer "B.Cu")
			(hatch none 0.5)
			(connect_pads
				(clearance 0)
			)
			(min_thickness 0.25)
			(keepout
				(tracks not_allowed)
				(vias allowed)
				(pads allowed)
				(copperpour not_allowed)
				(footprints allowed)
			)
			(placement
				(enabled no)
				(sheetname "")
			)
			(fill
				(thermal_gap 0.5)
				(thermal_bridge_width 0.5)
				(island_removal_mode 0)
			)
			(polygon
				(pts
					(xy 321.8307 -33.19018) (xy 321.8307 -32.68218) (xy 321.4497 -32.68218) (xy 321.4497 -33.19018)
				)
			)
		)
	)
	(footprint ""
		(layer "B.Cu")
		(at 409.3845 -26.035 -90)
		(property "Reference" "C25W69"
			(at -0.97536 0.76708 0)
			(unlocked yes)
			(layer "B.SilkS")
			(effects
				(font
					(size 0.4064 0.254)
					(thickness 0.1524)
				)
				(justify mirror)
			)
		)
		(property "Value" ""
			(at 0 0 90)
			(layer "B.Fab")
			(effects
				(font
					(size 1.27 1.27)
				)
				(justify mirror)
			)
		)
		(duplicate_pad_numbers_are_jumpers no)
		(fp_poly
			(pts
				(xy 0.4953 -0.2032) (xy -0.4953 -0.2032) (xy -0.4953 1.6002) (xy 0.4953 1.6002)
			)
			(stroke
				(width 0)
				(type default)
			)
			(fill no)
			(layer "B.CrtYd")
		)
		(fp_line
			(start -0.4953 1.6002)
			(end 0.4953 1.6002)
			(stroke
				(width 0.1)
				(type default)
			)
			(layer "B.Fab")
		)
		(fp_line
			(start 0.4953 1.6002)
			(end 0.4953 -0.2032)
			(stroke
				(width 0.1)
				(type default)
			)
			(layer "B.Fab")
		)
		(fp_line
			(start -0.4953 -0.2032)
			(end -0.4953 1.6002)
			(stroke
				(width 0.1)
				(type default)
			)
			(layer "B.Fab")
		)
		(fp_line
			(start 0.4953 -0.2032)
			(end -0.4953 -0.2032)
			(stroke
				(width 0.1)
				(type default)
			)
			(layer "B.Fab")
		)
		(pad "1" smd rect
			(at 0 0 90)
			(size 0.762 0.889)
			(layers "B.Cu" "B.Mask" "B.Paste")
			(net "VCC_VA_3V3")
		)
		(pad "2" smd rect
			(at 0 1.397 90)
			(size 0.762 0.889)
			(layers "B.Cu" "B.Mask" "B.Paste")
			(net "GND")
		)
		(zone
			(layer "B.Cu")
			(hatch none 0.5)
			(connect_pads
				(clearance 0)
			)
			(min_thickness 0.25)
			(keepout
				(tracks not_allowed)
				(vias allowed)
				(pads allowed)
				(copperpour not_allowed)
				(footprints allowed)
			)
			(placement
				(enabled no)
				(sheetname "")
			)
			(fill
				(thermal_gap 0.5)
				(thermal_bridge_width 0.5)
				(island_removal_mode 0)
			)
			(polygon
				(pts
					(xy 408.94 -25.654) (xy 408.94 -26.416) (xy 408.432 -26.416) (xy 408.432 -25.654)
				)
			)
		)
	)
)
